# S9S_MB_2U (Grand Teton) — schematic netlist excerpt (pin names and nets, part order shuffled) for the footprints in the layout excerpt that follows; sources: Cadence DE-HDL packaged netlist, KiCad conversion of 03242023_DA0F0TMBIJ0_F0T_Motherboard_J_brd_V01_OCP.brd

J18  SCONN288_ADR50017P087CC  SCONN288_ADR50017-P087CC IO  pkg DDR288S_1-1VXB  page 99
  VIN_BULK0  = P12V_S3_AUX_CPU1_NVDIMM
  RFU0  = TP_CHA_CPU1_DIMM2_FRU_0
  VIN_MGMT  = P3V3_AUX
  HSCL  = I3C_SPD_DDRABCD_CPU1_LVC1_SCL_1
  HSDA  = I3C_SPD_DDRABCD_CPU1_LVC1_SDA
  VSS0  = GND
  DQ0_A  = M_A_CPU1_SA_DQ<0>
  VSS1  = GND
  DQ1_A  = M_A_CPU1_SA_DQ<1>
  VSS2  = GND
  DQS0_A_T  = M_A_CPU1_SA_DQS_DP<0>
  DQS0_A_C  = M_A_CPU1_SA_DQS_DN<0>
  VSS3  = GND
  DQ4_A  = M_A_CPU1_SA_DQ<4>
  VSS4  = GND
  DQ5_A  = M_A_CPU1_SA_DQ<5>
  VSS5  = GND
  DQ8_A  = M_A_CPU1_SA_DQ<8>
  VSS6  = GND
  DQ9_A  = M_A_CPU1_SA_DQ<9>
  VSS7  = GND
  DQS1_A_T  = M_A_CPU1_SA_DQS_DP<1>
  DQS1_A_C  = M_A_CPU1_SA_DQS_DN<1>
  VSS8  = GND
  DQ12_A  = M_A_CPU1_SA_DQ<12>
  VSS9  = GND
  DQ13_A  = M_A_CPU1_SA_DQ<13>
  VSS10  = GND
  DQ16_A  = M_A_CPU1_SA_DQ<16>
  VSS11  = GND
  DQ17_A  = M_A_CPU1_SA_DQ<17>
  VSS12  = GND
  DQS2_A_T  = M_A_CPU1_SA_DQS_DP<2>
  DQS2_A_C  = M_A_CPU1_SA_DQS_DN<2>
  VSS13  = GND
  DQ20_A  = M_A_CPU1_SA_DQ<20>
  VSS14  = GND
  DQ21_A  = M_A_CPU1_SA_DQ<21>
  VSS15  = GND
  DQ24_A  = M_A_CPU1_SA_DQ<24>
  VSS16  = GND
  DQ25_A  = M_A_CPU1_SA_DQ<25>
  VSS17  = GND
  DQS3_A_T  = M_A_CPU1_SA_DQS_DP<3>
  DQS3_A_C  = M_A_CPU1_SA_DQS_DN<3>
  VSS18  = GND
  DQ28_A  = M_A_CPU1_SA_DQ<28>
  VSS19  = GND
  DQ29_A  = M_A_CPU1_SA_DQ<29>
  VSS20  = GND
  CB0_A  = M_A_CPU1_SA_CB<0>
  VSS21  = GND
  CB1_A  = M_A_CPU1_SA_CB<1>
  VSS22  = GND
  DQS4_A_T  = M_A_CPU1_SA_DQS_DP<4>
  DQS4_A_C  = M_A_CPU1_SA_DQS_DN<4>
  VSS23  = GND
  CB4_A  = M_A_CPU1_SA_CB<4>
  VSS24  = GND
  CB5_A  = M_A_CPU1_SA_CB<5>
  VSS25  = GND
  ALERT_N  = M_A_CPU1_ALERT_N
  VSS26  = GND
  CS0_A_N  = M_A_CPU1_SA_CS_N<2>
  VSS27  = GND
  CA0_A  = M_A_CPU1_SA_CA<0>
  VSS28  = GND
  CA2_A  = M_A_CPU1_SA_CA<2>
  VSS29  = GND
  CA4_A  = M_A_CPU1_SA_CA<4>
  VSS30  = GND
  CA6_A  = M_A_CPU1_SA_CA<6>
  VSS31  = GND
  PAR_A  = M_A_CPU1_SA_PAR
  VSS32  = GND
  CA0_B  = M_A_CPU1_SB_CA<0>
  VSS33  = GND
  CA2_B  = M_A_CPU1_SB_CA<2>
  VSS34  = GND
  CA4_B  = M_A_CPU1_SB_CA<4>
  VSS35  = GND
  CA6_B  = M_A_CPU1_SB_CA<6>
  VSS36  = GND
  CS0_B_N  = M_A_CPU1_SB_CS_N<2>
  VSS37  = GND
  \lbd||rsp_a_n\  = M_A_CPU1_SA_RSP<1>
  \lbs||rsp_b_n\  = M_A_CPU1_SB_RSP<1>
  VSS38  = GND
  CB4_B  = M_A_CPU1_SB_CB<4>
  VSS39  = GND
  CB5_B  = M_A_CPU1_SB_CB<5>
  VSS40  = GND
  \dqs9_b_t||tdqs9_b_t||dbi4_b_n\  = M_A_CPU1_SB_DQS_DP<9>
  \dqs9_b_c||tdqs9_b_c\  = M_A_CPU1_SB_DQS_DN<9>
  VSS41  = GND
  CB0_B  = M_A_CPU1_SB_CB<0>
  VSS42  = GND
  CB1_B  = M_A_CPU1_SB_CB<1>
  VSS43  = GND
  DQ0_B  = M_A_CPU1_SB_DQ<0>
  VSS44  = GND
  DQ1_B  = M_A_CPU1_SB_DQ<1>
  VSS45  = GND
  DQS0_B_T  = M_A_CPU1_SB_DQS_DP<0>
  DQS0_B_C  = M_A_CPU1_SB_DQS_DN<0>
  VSS46  = GND
  DQ4_B  = M_A_CPU1_SB_DQ<4>
  VSS47  = GND
  DQ5_B  = M_A_CPU1_SB_DQ<5>
  VSS48  = GND
  DQ8_B  = M_A_CPU1_SB_DQ<8>
  VSS49  = GND
  DQ9_B  = M_A_CPU1_SB_DQ<9>
  VSS50  = GND
  DQS1_B_T  = M_A_CPU1_SB_DQS_DP<1>
  DQS1_B_C  = M_A_CPU1_SB_DQS_DN<1>
  VSS51  = GND
  DQ12_B  = M_A_CPU1_SB_DQ<12>
  VSS52  = GND
  DQ13_B  = M_A_CPU1_SB_DQ<13>
  VSS53  = GND
  DQ16_B  = M_A_CPU1_SB_DQ<16>
  VSS54  = GND
  DQ17_B  = M_A_CPU1_SB_DQ<17>
  VSS55  = GND
  DQS2_B_T  = M_A_CPU1_SB_DQS_DP<2>
  DQS2_B_C  = M_A_CPU1_SB_DQS_DN<2>
  VSS56  = GND
  DQ20_B  = M_A_CPU1_SB_DQ<20>
  VSS57  = GND
  DQ21_B  = M_A_CPU1_SB_DQ<21>
  VSS58  = GND
  DQ24_B  = M_A_CPU1_SB_DQ<24>
  VSS59  = GND
  DQ25_B  = M_A_CPU1_SB_DQ<25>
  VSS60  = GND
  DQS3_B_T  = M_A_CPU1_SB_DQS_DP<3>
  DQS3_B_C  = M_A_CPU1_SB_DQS_DN<3>
  VSS61  = GND
  DQ28_B  = M_A_CPU1_SB_DQ<28>
  VSS62  = GND
  DQ29_B  = M_A_CPU1_SB_DQ<29>
  VSS63  = GND
  RFU1  = TP_CHA_CPU1_DIMM2_FRU_1
  VIN_BULK1  = P12V_S3_AUX_CPU1_NVDIMM
  VIN_BULK2  = P12V_S3_AUX_CPU1_NVDIMM
  \pwr_good||fail_n\  = PWRGD_CHA_CPU1_DIMM2
  HSA  = PD_CHA_CPU1_DIMM2_SAA
  RFU2  = TP_CHA_CPU1_DIMM2_FRU_2
  RFU3  = TP_CHA_CPU1_DIMM2_FRU_3
  VSS64  = GND
  DQ2_A  = M_A_CPU1_SA_DQ<2>
  VSS65  = GND
  DQ3_A  = M_A_CPU1_SA_DQ<3>
  VSS66  = GND
  \dqs5_a_c||tdqs5_a_c||dqs5_a_t||tdqs5_a_t\  = M_A_CPU1_SA_DQS_DN<5>
  \dqs5_a_t||tdqs5_a_t\  = M_A_CPU1_SA_DQS_DP<5>
  VSS67  = GND
  DQ6_A  = M_A_CPU1_SA_DQ<6>
  VSS68  = GND
  DQ7_A  = M_A_CPU1_SA_DQ<7>
  VSS69  = GND
  DQ10_A  = M_A_CPU1_SA_DQ<10>
  VSS70  = GND
  DQ11_A  = M_A_CPU1_SA_DQ<11>
  VSS71  = GND
  \dqs6_a_c||tdqs6_a_c||dqs6_a_t||tdqs6_a_t\  = M_A_CPU1_SA_DQS_DN<6>
  \dqs6_a_t||tdqs6_a_t\  = M_A_CPU1_SA_DQS_DP<6>
  VSS72  = GND
  DQ14_A  = M_A_CPU1_SA_DQ<14>
  VSS73  = GND
  DQ15_A  = M_A_CPU1_SA_DQ<15>
  VSS74  = GND
  DQ18_A  = M_A_CPU1_SA_DQ<18>
  VSS75  = GND
  DQ19_A  = M_A_CPU1_SA_DQ<19>
  VSS76  = GND
  \dqs7_a_c||tdqs7_a_c\  = M_A_CPU1_SA_DQS_DN<7>
  \dqs7_a_t||tdqs7_a_t\  = M_A_CPU1_SA_DQS_DP<7>
  VSS77  = GND
  DQ22_A  = M_A_CPU1_SA_DQ<22>
  VSS78  = GND
  DQ23_A  = M_A_CPU1_SA_DQ<23>
  VSS79  = GND
  DQ26_A  = M_A_CPU1_SA_DQ<26>
  VSS80  = GND
  DQ27_A  = M_A_CPU1_SA_DQ<27>
  VSS81  = GND
  \dqs8_a_c||tdqs8_a_c\  = M_A_CPU1_SA_DQS_DN<8>
  \dqs8_a_t||tdqs8_a_t\  = M_A_CPU1_SA_DQS_DP<8>
  VSS82  = GND
  DQ30_A  = M_A_CPU1_SA_DQ<30>
  VSS83  = GND
  DQ31_A  = M_A_CPU1_SA_DQ<31>
  VSS84  = GND
  CB2_A  = M_A_CPU1_SA_CB<2>
  VSS85  = GND
  CB3_A  = M_A_CPU1_SA_CB<3>
  VSS86  = GND
  \dqs9_a_c||tdqs9_a_c\  = M_A_CPU1_SA_DQS_DN<9>
  \dqs9_a_t||tdqs9_a_t\  = M_A_CPU1_SA_DQS_DP<9>
  VSS87  = GND
  CB6_A  = M_A_CPU1_SA_CB<6>
  VSS88  = GND
  CB7_A  = M_A_CPU1_SA_CB<7>
  VSS89  = GND
  RESET_N  = RST_M_AB_CPU1_FPGA_N
  VSS90  = GND
  CS1_A_N  = M_A_CPU1_SA_CS_N<3>
  VSS91  = GND
  CA1_A  = M_A_CPU1_SA_CA<1>
  VSS92  = GND
  CA3_A  = M_A_CPU1_SA_CA<3>
  VSS93  = GND
  CA5_A  = M_A_CPU1_SA_CA<5>
  VSS94  = GND
  CK_T  = M_A_CPU1_CLK_DP<1>
  CK_C  = M_A_CPU1_CLK_DN<1>
  VSS95  = GND
  RFU4  = TP_CHA_CPU1_DIMM2_FRU_4
  CA1_B  = M_A_CPU1_SB_CA<1>
  VSS96  = GND
  CA3_B  = M_A_CPU1_SB_CA<3>
  VSS97  = GND
  CA5_B  = M_A_CPU1_SB_CA<5>
  VSS98  = GND
  PAR_B  = M_A_CPU1_SB_PAR
  VSS99  = GND
  CS1_B_N  = M_A_CPU1_SB_CS_N<3>
  VSS100  = GND
  RFU5  = TP_CHA_CPU1_DIMM2_FRU_5
  RFU6  = TP_CHA_CPU1_DIMM2_FRU_6
  VSS101  = GND
  CB6_B  = M_A_CPU1_SB_CB<6>
  VSS102  = GND
  CB7_B  = M_A_CPU1_SB_CB<7>
  VSS103  = GND
  DQS4_B_C  = M_A_CPU1_SB_DQS_DN<4>
  DQS4_B_T  = M_A_CPU1_SB_DQS_DP<4>
  VSS104  = GND
  CB2_B  = M_A_CPU1_SB_CB<2>
  VSS105  = GND
  CB3_B  = M_A_CPU1_SB_CB<3>
  VSS106  = GND
  DQ2_B  = M_A_CPU1_SB_DQ<2>
  VSS107  = GND
  DQ3_B  = M_A_CPU1_SB_DQ<3>
  VSS108  = GND
  \dqs5_b_c||tdqs5_b_c\  = M_A_CPU1_SB_DQS_DN<5>
  \dqs5_b_t||tdqs5_b_t\  = M_A_CPU1_SB_DQS_DP<5>
  VSS109  = GND
  DQ6_B  = M_A_CPU1_SB_DQ<6>
  VSS110  = GND
  DQ7_B  = M_A_CPU1_SB_DQ<7>
  VSS111  = GND
  DQ10_B  = M_A_CPU1_SB_DQ<10>
  VSS112  = GND
  DQ11_B  = M_A_CPU1_SB_DQ<11>
  VSS113  = GND
  \dqs6_b_c||tdqs6_b_c\  = M_A_CPU1_SB_DQS_DN<6>
  \dqs6_b_t||tdqs6_b_t\  = M_A_CPU1_SB_DQS_DP<6>
  VSS114  = GND
  DQ14_B  = M_A_CPU1_SB_DQ<14>
  VSS115  = GND
  DQ15_B  = M_A_CPU1_SB_DQ<15>
  VSS116  = GND
  DQ18_B  = M_A_CPU1_SB_DQ<18>
  VSS117  = GND
  DQ19_B  = M_A_CPU1_SB_DQ<19>
  VSS118  = GND
  \dqs7_b_c||tdqs7_b_c\  = M_A_CPU1_SB_DQS_DN<7>
  \dqs7_b_t||tdqs7_b_t\  = M_A_CPU1_SB_DQS_DP<7>
  VSS119  = GND
  DQ22_B  = M_A_CPU1_SB_DQ<22>
  VSS120  = GND
  DQ23_B  = M_A_CPU1_SB_DQ<23>
  VSS121  = GND
  DQ26_B  = M_A_CPU1_SB_DQ<26>
  VSS122  = GND
  DQ27_B  = M_A_CPU1_SB_DQ<27>
  VSS123  = GND
  \dqs8_b_c||tdqs8_b_c\  = M_A_CPU1_SB_DQS_DN<8>
  \dqs8_b_t||tdqs8_b_t\  = M_A_CPU1_SB_DQS_DP<8>
  VSS124  = GND
  DQ30_B  = M_A_CPU1_SB_DQ<30>
  VSS125  = GND
  DQ31_B  = M_A_CPU1_SB_DQ<31>
  VSS126  = GND
  G1  = GND
  G2  = GND
  G3  = GND

(kicad_pcb
	(version 20260206)
	(generator "pcbnew")
	(generator_version "10.0")
	(general
		(thickness 1.6)
		(legacy_teardrops no)
	)
	(paper "A4")
	(title_block
		(title "03242023_DA0F0TMBIJ0_F0T_Motherboard_J_brd_V01_OCP.brd")
		(comment 1 "Grand Teton / footprint 3819 of 6105 (J18), pads 183-228 of 291")
	)
	(layers
		(0 "F.Cu" signal "TOP")
		(4 "In1.Cu" signal "GND")
		(6 "In2.Cu" signal "IN1")
		(8 "In3.Cu" signal "GND1")
		(10 "In4.Cu" signal "IN2")
		(12 "In5.Cu" signal "GND2")
		(14 "In6.Cu" signal "IN3")
		(16 "In7.Cu" signal "GND3")
		(18 "In8.Cu" signal "VCC")
		(20 "In9.Cu" signal "VCC1")
		(22 "In10.Cu" signal "GND4")
		(24 "In11.Cu" signal "IN4")
		(26 "In12.Cu" signal "GND5")
		(28 "In13.Cu" signal "IN5")
		(30 "In14.Cu" signal "GND6")
		(32 "In15.Cu" signal "IN6")
		(34 "In16.Cu" signal "GND7")
		(2 "B.Cu" signal "BOTTOM")
		(9 "F.Adhes" user "F.Adhesive")
		(11 "B.Adhes" user "B.Adhesive")
		(13 "F.Paste" user "Package Geometry/Pastemask Top")
		(15 "B.Paste" user "Package Geometry/Pastemask Bottom")
		(5 "F.SilkS" user "Ref Des/Silkscreen Top")
		(7 "B.SilkS" user "Ref Des/Silkscreen Bottom")
		(1 "F.Mask" user "Board Geometry/Soldermask Top")
		(3 "B.Mask" user "Board Geometry/Soldermask Bottom")
		(17 "Dwgs.User" user "User.Drawings")
		(19 "Cmts.User" user "User.Comments")
		(21 "Eco1.User" user "User.Eco1")
		(23 "Eco2.User" user "User.Eco2")
		(25 "Edge.Cuts" user "Board Geometry/Outline")
		(27 "Margin" user)
		(31 "F.CrtYd" user "Package Geometry/Place Bound Top")
		(29 "B.CrtYd" user "Package Geometry/Place Bound Bottom")
		(35 "F.Fab" user "Ref Des/Assembly Top")
		(33 "B.Fab" user "Ref Des/Assembly Bottom")
	)
	(footprint ""
		(layer "F.Cu")
		(at 62.99708 -258.091686)
		(property "Reference" "J18"
			(at -1.547622 -81.836514 0)
			(unlocked yes)
			(layer "F.SilkS")
			(effects
				(font
					(size 0.7874 0.5842)
					(thickness 0.1524)
				)
				(justify left)
			)
		)
		(property "Value" ""
			(at 0 0 0)
			(layer "F.Fab")
			(effects
				(font
					(size 1.27 1.27)
				)
			)
		)
		(duplicate_pad_numbers_are_jumpers no)
		(pad "183" smd rect
			(at 2.050034 -31.025084 270)
			(size 0.519938 1.4986)
			(layers "F.Cu" "F.Mask" "F.Paste")
			(net "M_A_CPU1_SA_DQ<23>")
		)
		(pad "184" smd rect
			(at 2.050034 -30.174946 270)
			(size 0.519938 1.4986)
			(layers "F.Cu" "F.Mask" "F.Paste")
			(net "GND")
		)
		(pad "185" smd rect
			(at 2.050034 -29.325062 270)
			(size 0.519938 1.4986)
			(layers "F.Cu" "F.Mask" "F.Paste")
			(net "M_A_CPU1_SA_DQ<26>")
		)
		(pad "186" smd rect
			(at 2.050034 -28.474924 270)
			(size 0.519938 1.4986)
			(layers "F.Cu" "F.Mask" "F.Paste")
			(net "GND")
		)
		(pad "187" smd rect
			(at 2.050034 -27.62504 270)
			(size 0.519938 1.4986)
			(layers "F.Cu" "F.Mask" "F.Paste")
			(net "M_A_CPU1_SA_DQ<27>")
		)
		(pad "188" smd rect
			(at 2.050034 -26.774902 270)
			(size 0.519938 1.4986)
			(layers "F.Cu" "F.Mask" "F.Paste")
			(net "GND")
		)
		(pad "189" smd rect
			(at 2.050034 -25.925018 270)
			(size 0.519938 1.4986)
			(layers "F.Cu" "F.Mask" "F.Paste")
			(net "M_A_CPU1_SA_DQS_DN<8>")
		)
		(pad "190" smd rect
			(at 2.050034 -25.07488 270)
			(size 0.519938 1.4986)
			(layers "F.Cu" "F.Mask" "F.Paste")
			(net "M_A_CPU1_SA_DQS_DP<8>")
		)
		(pad "191" smd rect
			(at 2.050034 -24.224996 270)
			(size 0.519938 1.4986)
			(layers "F.Cu" "F.Mask" "F.Paste")
			(net "GND")
		)
		(pad "192" smd rect
			(at 2.050034 -23.375112 270)
			(size 0.519938 1.4986)
			(layers "F.Cu" "F.Mask" "F.Paste")
			(net "M_A_CPU1_SA_DQ<30>")
		)
		(pad "193" smd rect
			(at 2.050034 -22.524974 270)
			(size 0.519938 1.4986)
			(layers "F.Cu" "F.Mask" "F.Paste")
			(net "GND")
		)
		(pad "194" smd rect
			(at 2.050034 -21.67509 270)
			(size 0.519938 1.4986)
			(layers "F.Cu" "F.Mask" "F.Paste")
			(net "M_A_CPU1_SA_DQ<31>")
		)
		(pad "195" smd rect
			(at 2.050034 -20.824952 270)
			(size 0.519938 1.4986)
			(layers "F.Cu" "F.Mask" "F.Paste")
			(net "GND")
		)
		(pad "196" smd rect
			(at 2.050034 -19.975068 270)
			(size 0.519938 1.4986)
			(layers "F.Cu" "F.Mask" "F.Paste")
			(net "M_A_CPU1_SA_CB<2>")
		)
		(pad "197" smd rect
			(at 2.050034 -19.12493 270)
			(size 0.519938 1.4986)
			(layers "F.Cu" "F.Mask" "F.Paste")
			(net "GND")
		)
		(pad "198" smd rect
			(at 2.050034 -18.275046 270)
			(size 0.519938 1.4986)
			(layers "F.Cu" "F.Mask" "F.Paste")
			(net "M_A_CPU1_SA_CB<3>")
		)
		(pad "199" smd rect
			(at 2.050034 -17.424908 270)
			(size 0.519938 1.4986)
			(layers "F.Cu" "F.Mask" "F.Paste")
			(net "GND")
		)
		(pad "200" smd rect
			(at 2.050034 -16.575024 270)
			(size 0.519938 1.4986)
			(layers "F.Cu" "F.Mask" "F.Paste")
			(net "M_A_CPU1_SA_DQS_DN<9>")
		)
		(pad "201" smd rect
			(at 2.050034 -15.724886 270)
			(size 0.519938 1.4986)
			(layers "F.Cu" "F.Mask" "F.Paste")
			(net "M_A_CPU1_SA_DQS_DP<9>")
		)
		(pad "202" smd rect
			(at 2.050034 -14.875002 270)
			(size 0.519938 1.4986)
			(layers "F.Cu" "F.Mask" "F.Paste")
			(net "GND")
		)
		(pad "203" smd rect
			(at 2.050034 -14.025118 270)
			(size 0.519938 1.4986)
			(layers "F.Cu" "F.Mask" "F.Paste")
			(net "M_A_CPU1_SA_CB<6>")
		)
		(pad "204" smd rect
			(at 2.050034 -13.17498 270)
			(size 0.519938 1.4986)
			(layers "F.Cu" "F.Mask" "F.Paste")
			(net "GND")
		)
		(pad "205" smd rect
			(at 2.050034 -12.325096 270)
			(size 0.519938 1.4986)
			(layers "F.Cu" "F.Mask" "F.Paste")
			(net "M_A_CPU1_SA_CB<7>")
		)
		(pad "206" smd rect
			(at 2.050034 -11.474958 270)
			(size 0.519938 1.4986)
			(layers "F.Cu" "F.Mask" "F.Paste")
			(net "GND")
		)
		(pad "207" smd rect
			(at 2.050034 -10.625074 270)
			(size 0.519938 1.4986)
			(layers "F.Cu" "F.Mask" "F.Paste")
			(net "RST_M_AB_CPU1_FPGA_N")
		)
		(pad "208" smd rect
			(at 2.050034 -9.774936 270)
			(size 0.519938 1.4986)
			(layers "F.Cu" "F.Mask" "F.Paste")
			(net "GND")
		)
		(pad "209" smd rect
			(at 2.050034 -8.925052 270)
			(size 0.519938 1.4986)
			(layers "F.Cu" "F.Mask" "F.Paste")
			(net "M_A_CPU1_SA_CS_N<3>")
		)
		(pad "210" smd rect
			(at 2.050034 -8.074914 270)
			(size 0.519938 1.4986)
			(layers "F.Cu" "F.Mask" "F.Paste")
			(net "GND")
		)
		(pad "211" smd rect
			(at 2.050034 -7.22503 270)
			(size 0.519938 1.4986)
			(layers "F.Cu" "F.Mask" "F.Paste")
			(net "M_A_CPU1_SA_CA<1>")
		)
		(pad "212" smd rect
			(at 2.050034 -6.374892 270)
			(size 0.519938 1.4986)
			(layers "F.Cu" "F.Mask" "F.Paste")
			(net "GND")
		)
		(pad "213" smd rect
			(at 2.050034 -5.525008 270)
			(size 0.519938 1.4986)
			(layers "F.Cu" "F.Mask" "F.Paste")
			(net "M_A_CPU1_SA_CA<3>")
		)
		(pad "214" smd rect
			(at 2.050034 -4.675124 270)
			(size 0.519938 1.4986)
			(layers "F.Cu" "F.Mask" "F.Paste")
			(net "GND")
		)
		(pad "215" smd rect
			(at 2.050034 -3.824986 270)
			(size 0.519938 1.4986)
			(layers "F.Cu" "F.Mask" "F.Paste")
			(net "M_A_CPU1_SA_CA<5>")
		)
		(pad "216" smd rect
			(at 2.050034 -2.975102 270)
			(size 0.519938 1.4986)
			(layers "F.Cu" "F.Mask" "F.Paste")
			(net "GND")
		)
		(pad "217" smd rect
			(at 2.050034 -2.124964 270)
			(size 0.519938 1.4986)
			(layers "F.Cu" "F.Mask" "F.Paste")
			(net "M_A_CPU1_CLK_DP<1>")
		)
		(pad "218" smd rect
			(at 2.050034 -1.27508 270)
			(size 0.519938 1.4986)
			(layers "F.Cu" "F.Mask" "F.Paste")
			(net "M_A_CPU1_CLK_DN<1>")
		)
		(pad "219" smd rect
			(at 2.050034 -0.424942 270)
			(size 0.519938 1.4986)
			(layers "F.Cu" "F.Mask" "F.Paste")
			(net "GND")
		)
		(pad "220" smd rect
			(at 2.050034 5.525008 270)
			(size 0.519938 1.4986)
			(layers "F.Cu" "F.Mask" "F.Paste")
			(net "TP_CHA_CPU1_DIMM2_FRU_4")
		)
		(pad "221" smd rect
			(at 2.050034 6.374892 270)
			(size 0.519938 1.4986)
			(layers "F.Cu" "F.Mask" "F.Paste")
			(net "M_A_CPU1_SB_CA<1>")
		)
		(pad "222" smd rect
			(at 2.050034 7.22503 270)
			(size 0.519938 1.4986)
			(layers "F.Cu" "F.Mask" "F.Paste")
			(net "GND")
		)
		(pad "223" smd rect
			(at 2.050034 8.074914 270)
			(size 0.519938 1.4986)
			(layers "F.Cu" "F.Mask" "F.Paste")
			(net "M_A_CPU1_SB_CA<3>")
		)
		(pad "224" smd rect
			(at 2.050034 8.925052 270)
			(size 0.519938 1.4986)
			(layers "F.Cu" "F.Mask" "F.Paste")
			(net "GND")
		)
		(pad "225" smd rect
			(at 2.050034 9.774936 270)
			(size 0.519938 1.4986)
			(layers "F.Cu" "F.Mask" "F.Paste")
			(net "M_A_CPU1_SB_CA<5>")
		)
		(pad "226" smd rect
			(at 2.050034 10.625074 270)
			(size 0.519938 1.4986)
			(layers "F.Cu" "F.Mask" "F.Paste")
			(net "GND")
		)
		(pad "227" smd rect
			(at 2.050034 11.474958 270)
			(size 0.519938 1.4986)
			(layers "F.Cu" "F.Mask" "F.Paste")
			(net "M_A_CPU1_SB_PAR")
		)
		(pad "228" smd rect
			(at 2.050034 12.325096 270)
			(size 0.519938 1.4986)
			(layers "F.Cu" "F.Mask" "F.Paste")
			(net "GND")
		)
	)
)
